# S9S_MB_2U (Grand Teton) — schematic netlist excerpt (pin names and nets, part order shuffled) for the footprints in the layout excerpt that follows; sources: Cadence DE-HDL packaged netlist, KiCad conversion of 03242023_DA0F0TMBIJ0_F0T_Motherboard_J_brd_V01_OCP.brd

R113  Q_RES  33.2 1% CHIP  pkg 0402LF  page 223 : A = FM_PLD_CLKS_OE_R_N ; B = FM_DB2000_OE_N
R3688  Q_RES  0 5% CHIP  pkg 0402LF  page 250 : A = P1V581_PDB_ADC ; B = P3V3_PDB_AUX_ADC_TIC

(kicad_pcb
	(version 20260206)
	(generator "pcbnew")
	(generator_version "10.0")
	(general
		(thickness 1.6)
		(legacy_teardrops no)
	)
	(paper "A4")
	(title_block
		(title "03242023_DA0F0TMBIJ0_F0T_Motherboard_J_brd_V01_OCP.brd")
		(comment 1 "Grand Teton / footprints 947-948 of 6105")
	)
	(layers
		(0 "F.Cu" signal "TOP")
		(4 "In1.Cu" signal "GND")
		(6 "In2.Cu" signal "IN1")
		(8 "In3.Cu" signal "GND1")
		(10 "In4.Cu" signal "IN2")
		(12 "In5.Cu" signal "GND2")
		(14 "In6.Cu" signal "IN3")
		(16 "In7.Cu" signal "GND3")
		(18 "In8.Cu" signal "VCC")
		(20 "In9.Cu" signal "VCC1")
		(22 "In10.Cu" signal "GND4")
		(24 "In11.Cu" signal "IN4")
		(26 "In12.Cu" signal "GND5")
		(28 "In13.Cu" signal "IN5")
		(30 "In14.Cu" signal "GND6")
		(32 "In15.Cu" signal "IN6")
		(34 "In16.Cu" signal "GND7")
		(2 "B.Cu" signal "BOTTOM")
		(9 "F.Adhes" user "F.Adhesive")
		(11 "B.Adhes" user "B.Adhesive")
		(13 "F.Paste" user "Package Geometry/Pastemask Top")
		(15 "B.Paste" user "Package Geometry/Pastemask Bottom")
		(5 "F.SilkS" user "Ref Des/Silkscreen Top")
		(7 "B.SilkS" user "Ref Des/Silkscreen Bottom")
		(1 "F.Mask" user "Board Geometry/Soldermask Top")
		(3 "B.Mask" user "Board Geometry/Soldermask Bottom")
		(17 "Dwgs.User" user "User.Drawings")
		(19 "Cmts.User" user "User.Comments")
		(21 "Eco1.User" user "User.Eco1")
		(23 "Eco2.User" user "User.Eco2")
		(25 "Edge.Cuts" user "Board Geometry/Outline")
		(27 "Margin" user)
		(31 "F.CrtYd" user "Package Geometry/Place Bound Top")
		(29 "B.CrtYd" user "Package Geometry/Place Bound Bottom")
		(35 "F.Fab" user "Ref Des/Assembly Top")
		(33 "B.Fab" user "Ref Des/Assembly Bottom")
	)
	(footprint ""
		(layer "F.Cu")
		(at 272.08607 -97.063814)
		(property "Reference" "R113"
			(at 0 0 0)
			(layer "F.SilkS")
			(hide yes)
			(effects
				(font
					(size 1.27 1.27)
				)
			)
		)
		(property "Value" ""
			(at 0 0 0)
			(layer "F.Fab")
			(effects
				(font
					(size 1.27 1.27)
				)
			)
		)
		(duplicate_pad_numbers_are_jumpers no)
		(fp_line
			(start -0.7874 -0.4064)
			(end 0.7874 -0.4064)
			(stroke
				(width 0.1524)
				(type default)
			)
			(layer "F.SilkS")
		)
		(fp_line
			(start -0.7874 0.4064)
			(end -0.7874 -0.4064)
			(stroke
				(width 0.1524)
				(type default)
			)
			(layer "F.SilkS")
		)
		(fp_line
			(start 0.7874 -0.4064)
			(end 0.7874 0.4064)
			(stroke
				(width 0.1524)
				(type default)
			)
			(layer "F.SilkS")
		)
		(fp_line
			(start 0.7874 0.4064)
			(end -0.7874 0.4064)
			(stroke
				(width 0.1524)
				(type default)
			)
			(layer "F.SilkS")
		)
		(fp_line
			(start -0.67945 -0.305054)
			(end -0.12065 -0.305054)
			(stroke
				(width 0.1)
				(type default)
			)
			(layer "F.Fab")
		)
		(fp_line
			(start -0.67945 0.3048)
			(end -0.67945 -0.305054)
			(stroke
				(width 0.1)
				(type default)
			)
			(layer "F.Fab")
		)
		(fp_line
			(start -0.12065 -0.305054)
			(end -0.12065 -0.2794)
			(stroke
				(width 0.1)
				(type default)
			)
			(layer "F.Fab")
		)
		(fp_line
			(start -0.12065 -0.2794)
			(end 0.12065 -0.2794)
			(stroke
				(width 0.1)
				(type default)
			)
			(layer "F.Fab")
		)
		(fp_line
			(start -0.12065 0.2794)
			(end -0.12065 0.3048)
			(stroke
				(width 0.1)
				(type default)
			)
			(layer "F.Fab")
		)
		(fp_line
			(start -0.12065 0.3048)
			(end -0.67945 0.3048)
			(stroke
				(width 0.1)
				(type default)
			)
			(layer "F.Fab")
		)
		(fp_line
			(start 0.120396 0.2794)
			(end -0.12065 0.2794)
			(stroke
				(width 0.1)
				(type default)
			)
			(layer "F.Fab")
		)
		(fp_line
			(start 0.120396 0.3048)
			(end 0.120396 0.2794)
			(stroke
				(width 0.1)
				(type default)
			)
			(layer "F.Fab")
		)
		(fp_line
			(start 0.12065 -0.3048)
			(end 0.67945 -0.3048)
			(stroke
				(width 0.1)
				(type default)
			)
			(layer "F.Fab")
		)
		(fp_line
			(start 0.12065 -0.2794)
			(end 0.12065 -0.3048)
			(stroke
				(width 0.1)
				(type default)
			)
			(layer "F.Fab")
		)
		(fp_line
			(start 0.67945 -0.3048)
			(end 0.67945 0.3048)
			(stroke
				(width 0.1)
				(type default)
			)
			(layer "F.Fab")
		)
		(fp_line
			(start 0.67945 0.3048)
			(end 0.120396 0.3048)
			(stroke
				(width 0.1)
				(type default)
			)
			(layer "F.Fab")
		)
		(pad "1" smd circle
			(at -0.40005 0)
			(size 0 0)
			(layers "F.Cu" "F.Mask" "F.Paste")
			(net "FM_PLD_CLKS_OE_R_N")
		)
		(pad "2" smd circle
			(at 0.40005 0)
			(size 0 0)
			(layers "F.Cu" "F.Mask" "F.Paste")
			(net "FM_DB2000_OE_N")
		)
	)
	(footprint ""
		(layer "F.Cu")
		(at 39.827454 -106.015282 180)
		(property "Reference" "R3688"
			(at 0 0 180)
			(layer "F.SilkS")
			(hide yes)
			(effects
				(font
					(size 1.27 1.27)
				)
			)
		)
		(property "Value" ""
			(at 0 0 180)
			(layer "F.Fab")
			(effects
				(font
					(size 1.27 1.27)
				)
			)
		)
		(duplicate_pad_numbers_are_jumpers no)
		(fp_line
			(start 0.7874 0.4064)
			(end -0.7874 0.4064)
			(stroke
				(width 0.1524)
				(type default)
			)
			(layer "F.SilkS")
		)
		(fp_line
			(start 0.7874 -0.4064)
			(end 0.7874 0.4064)
			(stroke
				(width 0.1524)
				(type default)
			)
			(layer "F.SilkS")
		)
		(fp_line
			(start -0.7874 0.4064)
			(end -0.7874 -0.4064)
			(stroke
				(width 0.1524)
				(type default)
			)
			(layer "F.SilkS")
		)
		(fp_line
			(start -0.7874 -0.4064)
			(end 0.7874 -0.4064)
			(stroke
				(width 0.1524)
				(type default)
			)
			(layer "F.SilkS")
		)
		(fp_line
			(start 0.67945 0.3048)
			(end 0.120396 0.3048)
			(stroke
				(width 0.1)
				(type default)
			)
			(layer "F.Fab")
		)
		(fp_line
			(start 0.67945 -0.3048)
			(end 0.67945 0.3048)
			(stroke
				(width 0.1)
				(type default)
			)
			(layer "F.Fab")
		)
		(fp_line
			(start 0.12065 -0.2794)
			(end 0.12065 -0.3048)
			(stroke
				(width 0.1)
				(type default)
			)
			(layer "F.Fab")
		)
		(fp_line
			(start 0.12065 -0.3048)
			(end 0.67945 -0.3048)
			(stroke
				(width 0.1)
				(type default)
			)
			(layer "F.Fab")
		)
		(fp_line
			(start 0.120396 0.3048)
			(end 0.120396 0.2794)
			(stroke
				(width 0.1)
				(type default)
			)
			(layer "F.Fab")
		)
		(fp_line
			(start 0.120396 0.2794)
			(end -0.12065 0.2794)
			(stroke
				(width 0.1)
				(type default)
			)
			(layer "F.Fab")
		)
		(fp_line
			(start -0.12065 0.3048)
			(end -0.67945 0.3048)
			(stroke
				(width 0.1)
				(type default)
			)
			(layer "F.Fab")
		)
		(fp_line
			(start -0.12065 0.2794)
			(end -0.12065 0.3048)
			(stroke
				(width 0.1)
				(type default)
			)
			(layer "F.Fab")
		)
		(fp_line
			(start -0.12065 -0.2794)
			(end 0.12065 -0.2794)
			(stroke
				(width 0.1)
				(type default)
			)
			(layer "F.Fab")
		)
		(fp_line
			(start -0.12065 -0.305054)
			(end -0.12065 -0.2794)
			(stroke
				(width 0.1)
				(type default)
			)
			(layer "F.Fab")
		)
		(fp_line
			(start -0.67945 0.3048)
			(end -0.67945 -0.305054)
			(stroke
				(width 0.1)
				(type default)
			)
			(layer "F.Fab")
		)
		(fp_line
			(start -0.67945 -0.305054)
			(end -0.12065 -0.305054)
			(stroke
				(width 0.1)
				(type default)
			)
			(layer "F.Fab")
		)
		(pad "1" smd rect
			(at -0.40005 0)
			(size 0.4572 0.508)
			(layers "F.Cu" "F.Mask" "F.Paste")
			(net "P1V581_PDB_ADC")
		)
		(pad "2" smd rect
			(at 0.40005 0)
			(size 0.4572 0.508)
			(layers "F.Cu" "F.Mask" "F.Paste")
			(net "P3V3_PDB_AUX_ADC_TIC")
		)
	)
)
